(kicad_pcb
	(version 20260206)
	(generator "pcbnew")
	(generator_version "10.0")
	(general
		(thickness 1.6)
		(legacy_teardrops no)
	)
	(paper "A4")
	(title_block
		(title "01162023_DA0F0TEBIF0_F0T_Expander_BD_F_brd_V02_OCP.brd")
		(comment 1 "Grand Teton / footprints 8974-8981 of 9728")
	)
	(layers
		(0 "F.Cu" signal "TOP")
		(4 "In1.Cu" signal "GND")
		(6 "In2.Cu" signal "VCC")
		(8 "In3.Cu" signal "VCC1")
		(10 "In4.Cu" signal "GND1")
		(12 "In5.Cu" signal "IN1")
		(14 "In6.Cu" signal "GND2")
		(16 "In7.Cu" signal "IN2")
		(18 "In8.Cu" signal "GND3")
		(20 "In9.Cu" signal "IN3")
		(22 "In10.Cu" signal "GND4")
		(24 "In11.Cu" signal "IN4")
		(26 "In12.Cu" signal "GND5")
		(28 "In13.Cu" signal "IN5")
		(30 "In14.Cu" signal "GND6")
		(32 "In15.Cu" signal "IN6")
		(34 "In16.Cu" signal "GND7")
		(2 "B.Cu" signal "BOTTOM")
		(9 "F.Adhes" user "F.Adhesive")
		(11 "B.Adhes" user "B.Adhesive")
		(13 "F.Paste" user "Package Geometry/Pastemask Top")
		(15 "B.Paste" user "Package Geometry/Pastemask Bottom")
		(5 "F.SilkS" user "Ref Des/Silkscreen Top")
		(7 "B.SilkS" user "Ref Des/Silkscreen Bottom")
		(1 "F.Mask" user "Board Geometry/Soldermask Top")
		(3 "B.Mask" user "Board Geometry/Soldermask Bottom")
		(17 "Dwgs.User" user "User.Drawings")
		(19 "Cmts.User" user "User.Comments")
		(21 "Eco1.User" user "User.Eco1")
		(23 "Eco2.User" user "User.Eco2")
		(25 "Edge.Cuts" user "Board Geometry/Outline")
		(27 "Margin" user)
		(31 "F.CrtYd" user "Package Geometry/Place Bound Top")
		(29 "B.CrtYd" user "Package Geometry/Place Bound Bottom")
		(35 "F.Fab" user "Ref Des/Assembly Top")
		(33 "B.Fab" user "Ref Des/Assembly Bottom")
	)
	(footprint ""
		(layer "B.Cu")
		(at 367.938812 -222.214186)
		(property "Reference" "R3502"
			(at 0 0 0)
			(layer "B.SilkS")
			(hide yes)
			(effects
				(font
					(size 1.27 1.27)
				)
				(justify mirror)
			)
		)
		(property "Value" ""
			(at 0 0 0)
			(layer "B.Fab")
			(effects
				(font
					(size 1.27 1.27)
				)
				(justify mirror)
			)
		)
		(duplicate_pad_numbers_are_jumpers no)
		(fp_line
			(start -0.7874 -0.4064)
			(end -0.7874 0.4064)
			(stroke
				(width 0.1524)
				(type default)
			)
			(layer "B.SilkS")
		)
		(fp_line
			(start -0.7874 0.4064)
			(end 0.7874 0.4064)
			(stroke
				(width 0.1524)
				(type default)
			)
			(layer "B.SilkS")
		)
		(fp_line
			(start 0.7874 -0.4064)
			(end -0.7874 -0.4064)
			(stroke
				(width 0.1524)
				(type default)
			)
			(layer "B.SilkS")
		)
		(fp_line
			(start 0.7874 0.4064)
			(end 0.7874 -0.4064)
			(stroke
				(width 0.1524)
				(type default)
			)
			(layer "B.SilkS")
		)
		(fp_line
			(start -0.67945 -0.3048)
			(end -0.67945 0.3048)
			(stroke
				(width 0.1)
				(type default)
			)
			(layer "B.Fab")
		)
		(fp_line
			(start -0.67945 0.3048)
			(end -0.120396 0.3048)
			(stroke
				(width 0.1)
				(type default)
			)
			(layer "B.Fab")
		)
		(fp_line
			(start -0.12065 -0.3048)
			(end -0.67945 -0.3048)
			(stroke
				(width 0.1)
				(type default)
			)
			(layer "B.Fab")
		)
		(fp_line
			(start -0.12065 -0.2794)
			(end -0.12065 -0.3048)
			(stroke
				(width 0.1)
				(type default)
			)
			(layer "B.Fab")
		)
		(fp_line
			(start -0.120396 0.2794)
			(end 0.12065 0.2794)
			(stroke
				(width 0.1)
				(type default)
			)
			(layer "B.Fab")
		)
		(fp_line
			(start -0.120396 0.3048)
			(end -0.120396 0.2794)
			(stroke
				(width 0.1)
				(type default)
			)
			(layer "B.Fab")
		)
		(fp_line
			(start 0.12065 -0.305054)
			(end 0.12065 -0.2794)
			(stroke
				(width 0.1)
				(type default)
			)
			(layer "B.Fab")
		)
		(fp_line
			(start 0.12065 -0.2794)
			(end -0.12065 -0.2794)
			(stroke
				(width 0.1)
				(type default)
			)
			(layer "B.Fab")
		)
		(fp_line
			(start 0.12065 0.2794)
			(end 0.12065 0.3048)
			(stroke
				(width 0.1)
				(type default)
			)
			(layer "B.Fab")
		)
		(fp_line
			(start 0.12065 0.3048)
			(end 0.67945 0.3048)
			(stroke
				(width 0.1)
				(type default)
			)
			(layer "B.Fab")
		)
		(fp_line
			(start 0.67945 -0.305054)
			(end 0.12065 -0.305054)
			(stroke
				(width 0.1)
				(type default)
			)
			(layer "B.Fab")
		)
		(fp_line
			(start 0.67945 0.3048)
			(end 0.67945 -0.305054)
			(stroke
				(width 0.1)
				(type default)
			)
			(layer "B.Fab")
		)
		(pad "1" smd circle
			(at 0.40005 0 180)
			(size 0 0)
			(layers "B.Cu" "B.Mask" "B.Paste")
			(net "SPI_PEX3_SDIO0_MUX")
		)
		(pad "2" smd circle
			(at -0.40005 0 180)
			(size 0 0)
			(layers "B.Cu" "B.Mask" "B.Paste")
			(net "SPI_PEX3_SDIO0_MUX_R")
		)
	)
	(footprint ""
		(layer "B.Cu")
		(at 349.123 -233.553 -90)
		(property "Reference" "R3604"
			(at 0 0 90)
			(layer "B.SilkS")
			(hide yes)
			(effects
				(font
					(size 1.27 1.27)
				)
				(justify mirror)
			)
		)
		(property "Value" ""
			(at 0 0 90)
			(layer "B.Fab")
			(effects
				(font
					(size 1.27 1.27)
				)
				(justify mirror)
			)
		)
		(duplicate_pad_numbers_are_jumpers no)
		(fp_line
			(start -0.7874 0.4064)
			(end 0.7874 0.4064)
			(stroke
				(width 0.1524)
				(type default)
			)
			(layer "B.SilkS")
		)
		(fp_line
			(start 0.7874 0.4064)
			(end 0.7874 -0.4064)
			(stroke
				(width 0.1524)
				(type default)
			)
			(layer "B.SilkS")
		)
		(fp_line
			(start -0.7874 -0.4064)
			(end -0.7874 0.4064)
			(stroke
				(width 0.1524)
				(type default)
			)
			(layer "B.SilkS")
		)
		(fp_line
			(start 0.7874 -0.4064)
			(end -0.7874 -0.4064)
			(stroke
				(width 0.1524)
				(type default)
			)
			(layer "B.SilkS")
		)
		(fp_line
			(start -0.67945 0.3048)
			(end -0.120396 0.3048)
			(stroke
				(width 0.1)
				(type default)
			)
			(layer "B.Fab")
		)
		(fp_line
			(start -0.120396 0.3048)
			(end -0.120396 0.2794)
			(stroke
				(width 0.1)
				(type default)
			)
			(layer "B.Fab")
		)
		(fp_line
			(start 0.12065 0.3048)
			(end 0.67945 0.3048)
			(stroke
				(width 0.1)
				(type default)
			)
			(layer "B.Fab")
		)
		(fp_line
			(start 0.67945 0.3048)
			(end 0.67945 -0.305054)
			(stroke
				(width 0.1)
				(type default)
			)
			(layer "B.Fab")
		)
		(fp_line
			(start -0.120396 0.2794)
			(end 0.12065 0.2794)
			(stroke
				(width 0.1)
				(type default)
			)
			(layer "B.Fab")
		)
		(fp_line
			(start 0.12065 0.2794)
			(end 0.12065 0.3048)
			(stroke
				(width 0.1)
				(type default)
			)
			(layer "B.Fab")
		)
		(fp_line
			(start -0.12065 -0.2794)
			(end -0.12065 -0.3048)
			(stroke
				(width 0.1)
				(type default)
			)
			(layer "B.Fab")
		)
		(fp_line
			(start 0.12065 -0.2794)
			(end -0.12065 -0.2794)
			(stroke
				(width 0.1)
				(type default)
			)
			(layer "B.Fab")
		)
		(fp_line
			(start -0.67945 -0.3048)
			(end -0.67945 0.3048)
			(stroke
				(width 0.1)
				(type default)
			)
			(layer "B.Fab")
		)
		(fp_line
			(start -0.12065 -0.3048)
			(end -0.67945 -0.3048)
			(stroke
				(width 0.1)
				(type default)
			)
			(layer "B.Fab")
		)
		(fp_line
			(start 0.12065 -0.305054)
			(end 0.12065 -0.2794)
			(stroke
				(width 0.1)
				(type default)
			)
			(layer "B.Fab")
		)
		(fp_line
			(start 0.67945 -0.305054)
			(end 0.12065 -0.305054)
			(stroke
				(width 0.1)
				(type default)
			)
			(layer "B.Fab")
		)
		(pad "1" smd circle
			(at 0.40005 0 90)
			(size 0 0)
			(layers "B.Cu" "B.Mask" "B.Paste")
			(net "RST_NIC0_PERST_N")
		)
		(pad "2" smd circle
			(at -0.40005 0 90)
			(size 0 0)
			(layers "B.Cu" "B.Mask" "B.Paste")
			(net "RST_NIC0_PERST_R_N")
		)
	)
	(footprint ""
		(layer "B.Cu")
		(at 392.749786 -299.224954)
		(property "Reference" "C3535"
			(at 0 0 0)
			(layer "B.SilkS")
			(hide yes)
			(effects
				(font
					(size 1.27 1.27)
				)
				(justify mirror)
			)
		)
		(property "Value" ""
			(at 0 0 0)
			(layer "B.Fab")
			(effects
				(font
					(size 1.27 1.27)
				)
				(justify mirror)
			)
		)
		(duplicate_pad_numbers_are_jumpers no)
		(fp_line
			(start -0.299974 -0.150114)
			(end -0.299974 0.150114)
			(stroke
				(width 0.1)
				(type default)
			)
			(layer "B.Fab")
		)
		(fp_line
			(start -0.299974 0.150114)
			(end 0.299974 0.150114)
			(stroke
				(width 0.1)
				(type default)
			)
			(layer "B.Fab")
		)
		(fp_line
			(start 0.299974 -0.150114)
			(end -0.299974 -0.150114)
			(stroke
				(width 0.1)
				(type default)
			)
			(layer "B.Fab")
		)
		(fp_line
			(start 0.299974 0.150114)
			(end 0.299974 -0.150114)
			(stroke
				(width 0.1)
				(type default)
			)
			(layer "B.Fab")
		)
		(pad "1" smd rect
			(at 0.2667 0 180)
			(size 0.3048 0.381)
			(layers "B.Cu" "B.Mask" "B.Paste")
			(net "P1V8_VDDA_PEX3")
		)
		(pad "2" smd rect
			(at -0.2667 0 180)
			(size 0.3048 0.381)
			(layers "B.Cu" "B.Mask" "B.Paste")
			(net "GND")
		)
	)
	(footprint ""
		(layer "B.Cu")
		(at 289.08375 -308.724808 -90)
		(property "Reference" "R1392"
			(at 0 0 90)
			(layer "B.SilkS")
			(hide yes)
			(effects
				(font
					(size 1.27 1.27)
				)
				(justify mirror)
			)
		)
		(property "Value" ""
			(at 0 0 90)
			(layer "B.Fab")
			(effects
				(font
					(size 1.27 1.27)
				)
				(justify mirror)
			)
		)
		(duplicate_pad_numbers_are_jumpers no)
		(fp_line
			(start -0.7874 0.4064)
			(end 0.7874 0.4064)
			(stroke
				(width 0.1524)
				(type default)
			)
			(layer "B.SilkS")
		)
		(fp_line
			(start 0.7874 0.4064)
			(end 0.7874 -0.4064)
			(stroke
				(width 0.1524)
				(type default)
			)
			(layer "B.SilkS")
		)
		(fp_line
			(start -0.7874 -0.4064)
			(end -0.7874 0.4064)
			(stroke
				(width 0.1524)
				(type default)
			)
			(layer "B.SilkS")
		)
		(fp_line
			(start 0.7874 -0.4064)
			(end -0.7874 -0.4064)
			(stroke
				(width 0.1524)
				(type default)
			)
			(layer "B.SilkS")
		)
		(fp_line
			(start -0.67945 0.3048)
			(end -0.120396 0.3048)
			(stroke
				(width 0.1)
				(type default)
			)
			(layer "B.Fab")
		)
		(fp_line
			(start -0.120396 0.3048)
			(end -0.120396 0.2794)
			(stroke
				(width 0.1)
				(type default)
			)
			(layer "B.Fab")
		)
		(fp_line
			(start 0.12065 0.3048)
			(end 0.67945 0.3048)
			(stroke
				(width 0.1)
				(type default)
			)
			(layer "B.Fab")
		)
		(fp_line
			(start 0.67945 0.3048)
			(end 0.67945 -0.305054)
			(stroke
				(width 0.1)
				(type default)
			)
			(layer "B.Fab")
		)
		(fp_line
			(start -0.120396 0.2794)
			(end 0.12065 0.2794)
			(stroke
				(width 0.1)
				(type default)
			)
			(layer "B.Fab")
		)
		(fp_line
			(start 0.12065 0.2794)
			(end 0.12065 0.3048)
			(stroke
				(width 0.1)
				(type default)
			)
			(layer "B.Fab")
		)
		(fp_line
			(start -0.12065 -0.2794)
			(end -0.12065 -0.3048)
			(stroke
				(width 0.1)
				(type default)
			)
			(layer "B.Fab")
		)
		(fp_line
			(start 0.12065 -0.2794)
			(end -0.12065 -0.2794)
			(stroke
				(width 0.1)
				(type default)
			)
			(layer "B.Fab")
		)
		(fp_line
			(start -0.67945 -0.3048)
			(end -0.67945 0.3048)
			(stroke
				(width 0.1)
				(type default)
			)
			(layer "B.Fab")
		)
		(fp_line
			(start -0.12065 -0.3048)
			(end -0.67945 -0.3048)
			(stroke
				(width 0.1)
				(type default)
			)
			(layer "B.Fab")
		)
		(fp_line
			(start 0.12065 -0.305054)
			(end 0.12065 -0.2794)
			(stroke
				(width 0.1)
				(type default)
			)
			(layer "B.Fab")
		)
		(fp_line
			(start 0.67945 -0.305054)
			(end 0.12065 -0.305054)
			(stroke
				(width 0.1)
				(type default)
			)
			(layer "B.Fab")
		)
		(pad "1" smd circle
			(at 0.40005 0 90)
			(size 0 0)
			(layers "B.Cu" "B.Mask" "B.Paste")
			(net "TP_PEX2_TRST_L")
		)
		(pad "2" smd circle
			(at -0.40005 0 90)
			(size 0 0)
			(layers "B.Cu" "B.Mask" "B.Paste")
			(net "GND")
		)
	)
	(footprint ""
		(layer "B.Cu")
		(at 56.883808 -308.724808 -90)
		(property "Reference" "R1256"
			(at 0 0 90)
			(layer "B.SilkS")
			(hide yes)
			(effects
				(font
					(size 1.27 1.27)
				)
				(justify mirror)
			)
		)
		(property "Value" ""
			(at 0 0 90)
			(layer "B.Fab")
			(effects
				(font
					(size 1.27 1.27)
				)
				(justify mirror)
			)
		)
		(duplicate_pad_numbers_are_jumpers no)
		(fp_line
			(start -0.7874 0.4064)
			(end 0.7874 0.4064)
			(stroke
				(width 0.1524)
				(type default)
			)
			(layer "B.SilkS")
		)
		(fp_line
			(start 0.7874 0.4064)
			(end 0.7874 -0.4064)
			(stroke
				(width 0.1524)
				(type default)
			)
			(layer "B.SilkS")
		)
		(fp_line
			(start -0.7874 -0.4064)
			(end -0.7874 0.4064)
			(stroke
				(width 0.1524)
				(type default)
			)
			(layer "B.SilkS")
		)
		(fp_line
			(start 0.7874 -0.4064)
			(end -0.7874 -0.4064)
			(stroke
				(width 0.1524)
				(type default)
			)
			(layer "B.SilkS")
		)
		(fp_line
			(start -0.67945 0.3048)
			(end -0.120396 0.3048)
			(stroke
				(width 0.1)
				(type default)
			)
			(layer "B.Fab")
		)
		(fp_line
			(start -0.120396 0.3048)
			(end -0.120396 0.2794)
			(stroke
				(width 0.1)
				(type default)
			)
			(layer "B.Fab")
		)
		(fp_line
			(start 0.12065 0.3048)
			(end 0.67945 0.3048)
			(stroke
				(width 0.1)
				(type default)
			)
			(layer "B.Fab")
		)
		(fp_line
			(start 0.67945 0.3048)
			(end 0.67945 -0.305054)
			(stroke
				(width 0.1)
				(type default)
			)
			(layer "B.Fab")
		)
		(fp_line
			(start -0.120396 0.2794)
			(end 0.12065 0.2794)
			(stroke
				(width 0.1)
				(type default)
			)
			(layer "B.Fab")
		)
		(fp_line
			(start 0.12065 0.2794)
			(end 0.12065 0.3048)
			(stroke
				(width 0.1)
				(type default)
			)
			(layer "B.Fab")
		)
		(fp_line
			(start -0.12065 -0.2794)
			(end -0.12065 -0.3048)
			(stroke
				(width 0.1)
				(type default)
			)
			(layer "B.Fab")
		)
		(fp_line
			(start 0.12065 -0.2794)
			(end -0.12065 -0.2794)
			(stroke
				(width 0.1)
				(type default)
			)
			(layer "B.Fab")
		)
		(fp_line
			(start -0.67945 -0.3048)
			(end -0.67945 0.3048)
			(stroke
				(width 0.1)
				(type default)
			)
			(layer "B.Fab")
		)
		(fp_line
			(start -0.12065 -0.3048)
			(end -0.67945 -0.3048)
			(stroke
				(width 0.1)
				(type default)
			)
			(layer "B.Fab")
		)
		(fp_line
			(start 0.12065 -0.305054)
			(end 0.12065 -0.2794)
			(stroke
				(width 0.1)
				(type default)
			)
			(layer "B.Fab")
		)
		(fp_line
			(start 0.67945 -0.305054)
			(end 0.12065 -0.305054)
			(stroke
				(width 0.1)
				(type default)
			)
			(layer "B.Fab")
		)
		(pad "1" smd circle
			(at 0.40005 0 90)
			(size 0 0)
			(layers "B.Cu" "B.Mask" "B.Paste")
			(net "TP_PEX0_TRST_L")
		)
		(pad "2" smd circle
			(at -0.40005 0 90)
			(size 0 0)
			(layers "B.Cu" "B.Mask" "B.Paste")
			(net "GND")
		)
	)
	(footprint ""
		(layer "B.Cu")
		(at 229.434644 -231.225598 90)
		(property "Reference" "R4554"
			(at 0 0 90)
			(layer "B.SilkS")
			(hide yes)
			(effects
				(font
					(size 1.27 1.27)
				)
				(justify mirror)
			)
		)
		(property "Value" ""
			(at 0 0 90)
			(layer "B.Fab")
			(effects
				(font
					(size 1.27 1.27)
				)
				(justify mirror)
			)
		)
		(duplicate_pad_numbers_are_jumpers no)
		(fp_line
			(start 0.7874 -0.4064)
			(end -0.7874 -0.4064)
			(stroke
				(width 0.1524)
				(type default)
			)
			(layer "B.SilkS")
		)
		(fp_line
			(start -0.7874 -0.4064)
			(end -0.7874 0.4064)
			(stroke
				(width 0.1524)
				(type default)
			)
			(layer "B.SilkS")
		)
		(fp_line
			(start 0.7874 0.4064)
			(end 0.7874 -0.4064)
			(stroke
				(width 0.1524)
				(type default)
			)
			(layer "B.SilkS")
		)
		(fp_line
			(start -0.7874 0.4064)
			(end 0.7874 0.4064)
			(stroke
				(width 0.1524)
				(type default)
			)
			(layer "B.SilkS")
		)
		(fp_line
			(start 0.67945 -0.305054)
			(end 0.12065 -0.305054)
			(stroke
				(width 0.1)
				(type default)
			)
			(layer "B.Fab")
		)
		(fp_line
			(start 0.12065 -0.305054)
			(end 0.12065 -0.2794)
			(stroke
				(width 0.1)
				(type default)
			)
			(layer "B.Fab")
		)
		(fp_line
			(start -0.12065 -0.3048)
			(end -0.67945 -0.3048)
			(stroke
				(width 0.1)
				(type default)
			)
			(layer "B.Fab")
		)
		(fp_line
			(start -0.67945 -0.3048)
			(end -0.67945 0.3048)
			(stroke
				(width 0.1)
				(type default)
			)
			(layer "B.Fab")
		)
		(fp_line
			(start 0.12065 -0.2794)
			(end -0.12065 -0.2794)
			(stroke
				(width 0.1)
				(type default)
			)
			(layer "B.Fab")
		)
		(fp_line
			(start -0.12065 -0.2794)
			(end -0.12065 -0.3048)
			(stroke
				(width 0.1)
				(type default)
			)
			(layer "B.Fab")
		)
		(fp_line
			(start 0.12065 0.2794)
			(end 0.12065 0.3048)
			(stroke
				(width 0.1)
				(type default)
			)
			(layer "B.Fab")
		)
		(fp_line
			(start -0.120396 0.2794)
			(end 0.12065 0.2794)
			(stroke
				(width 0.1)
				(type default)
			)
			(layer "B.Fab")
		)
		(fp_line
			(start 0.67945 0.3048)
			(end 0.67945 -0.305054)
			(stroke
				(width 0.1)
				(type default)
			)
			(layer "B.Fab")
		)
		(fp_line
			(start 0.12065 0.3048)
			(end 0.67945 0.3048)
			(stroke
				(width 0.1)
				(type default)
			)
			(layer "B.Fab")
		)
		(fp_line
			(start -0.120396 0.3048)
			(end -0.120396 0.2794)
			(stroke
				(width 0.1)
				(type default)
			)
			(layer "B.Fab")
		)
		(fp_line
			(start -0.67945 0.3048)
			(end -0.120396 0.3048)
			(stroke
				(width 0.1)
				(type default)
			)
			(layer "B.Fab")
		)
		(pad "1" smd circle
			(at 0.40005 0 270)
			(size 0 0)
			(layers "B.Cu" "B.Mask" "B.Paste")
			(net "GND")
		)
		(pad "2" smd circle
			(at -0.40005 0 270)
			(size 0 0)
			(layers "B.Cu" "B.Mask" "B.Paste")
			(net "BOARD_ID1")
		)
	)
	(footprint ""
		(layer "B.Cu")
		(at 181.44998 -303.499774 -90)
		(property "Reference" "C3083"
			(at 0 0 90)
			(layer "B.SilkS")
			(hide yes)
			(effects
				(font
					(size 1.27 1.27)
				)
				(justify mirror)
			)
		)
		(property "Value" ""
			(at 0 0 90)
			(layer "B.Fab")
			(effects
				(font
					(size 1.27 1.27)
				)
				(justify mirror)
			)
		)
		(duplicate_pad_numbers_are_jumpers no)
		(fp_line
			(start -0.299974 0.150114)
			(end 0.299974 0.150114)
			(stroke
				(width 0.1)
				(type default)
			)
			(layer "B.Fab")
		)
		(fp_line
			(start 0.299974 0.150114)
			(end 0.299974 -0.150114)
			(stroke
				(width 0.1)
				(type default)
			)
			(layer "B.Fab")
		)
		(fp_line
			(start -0.299974 -0.150114)
			(end -0.299974 0.150114)
			(stroke
				(width 0.1)
				(type default)
			)
			(layer "B.Fab")
		)
		(fp_line
			(start 0.299974 -0.150114)
			(end -0.299974 -0.150114)
			(stroke
				(width 0.1)
				(type default)
			)
			(layer "B.Fab")
		)
		(pad "1" smd rect
			(at 0.2667 0 90)
			(size 0.3048 0.381)
			(layers "B.Cu" "B.Mask" "B.Paste")
			(net "P1V25_PEX1")
		)
		(pad "2" smd rect
			(at -0.2667 0 90)
			(size 0.3048 0.381)
			(layers "B.Cu" "B.Mask" "B.Paste")
			(net "GND")
		)
	)
	(footprint ""
		(layer "B.Cu")
		(at 397.49984 -290.674806 180)
		(property "Reference" "C1871"
			(at 0 0 0)
			(layer "B.SilkS")
			(hide yes)
			(effects
				(font
					(size 1.27 1.27)
				)
				(justify mirror)
			)
		)
		(property "Value" ""
			(at 0 0 0)
			(layer "B.Fab")
			(effects
				(font
					(size 1.27 1.27)
				)
				(justify mirror)
			)
		)
		(duplicate_pad_numbers_are_jumpers no)
		(fp_line
			(start 0.299974 0.150114)
			(end 0.299974 -0.150114)
			(stroke
				(width 0.1)
				(type default)
			)
			(layer "B.Fab")
		)
		(fp_line
			(start 0.299974 -0.150114)
			(end -0.299974 -0.150114)
			(stroke
				(width 0.1)
				(type default)
			)
			(layer "B.Fab")
		)
		(fp_line
			(start -0.299974 0.150114)
			(end 0.299974 0.150114)
			(stroke
				(width 0.1)
				(type default)
			)
			(layer "B.Fab")
		)
		(fp_line
			(start -0.299974 -0.150114)
			(end -0.299974 0.150114)
			(stroke
				(width 0.1)
				(type default)
			)
			(layer "B.Fab")
		)
		(pad "1" smd rect
			(at 0.2667 0)
			(size 0.3048 0.381)
			(layers "B.Cu" "B.Mask" "B.Paste")
			(net "P0V8_PEX3")
		)
		(pad "2" smd rect
			(at -0.2667 0)
			(size 0.3048 0.381)
			(layers "B.Cu" "B.Mask" "B.Paste")
			(net "GND")
		)
	)
)
